(kicad_pcb
	(version 20260206)
	(generator "pcbnew")
	(generator_version "10.0")
	(general
		(thickness 1.6)
		(legacy_teardrops no)
	)
	(paper "A4")
	(title_block
		(title "04192023_DAF0TMB3IC0_F0TG_MB_C_brd_V02_OCP.brd")
		(comment 1 "Grand Teton / footprints 6979-6986 of 8354")
	)
	(layers
		(0 "F.Cu" signal "TOP")
		(4 "In1.Cu" signal "GND")
		(6 "In2.Cu" signal "IN1")
		(8 "In3.Cu" signal "GND1")
		(10 "In4.Cu" signal "IN2")
		(12 "In5.Cu" signal "GND2")
		(14 "In6.Cu" signal "IN3")
		(16 "In7.Cu" signal "GND3")
		(18 "In8.Cu" signal "VCC")
		(20 "In9.Cu" signal "VCC1")
		(22 "In10.Cu" signal "GND4")
		(24 "In11.Cu" signal "IN4")
		(26 "In12.Cu" signal "GND5")
		(28 "In13.Cu" signal "IN5")
		(30 "In14.Cu" signal "GND6")
		(32 "In15.Cu" signal "IN6")
		(34 "In16.Cu" signal "GND7")
		(2 "B.Cu" signal "BOTTOM")
		(9 "F.Adhes" user "F.Adhesive")
		(11 "B.Adhes" user "B.Adhesive")
		(13 "F.Paste" user "Package Geometry/Pastemask Top")
		(15 "B.Paste" user "Package Geometry/Pastemask Bottom")
		(5 "F.SilkS" user "Ref Des/Silkscreen Top")
		(7 "B.SilkS" user "Ref Des/Silkscreen Bottom")
		(1 "F.Mask" user "Board Geometry/Soldermask Top")
		(3 "B.Mask" user "Board Geometry/Soldermask Bottom")
		(17 "Dwgs.User" user "User.Drawings")
		(19 "Cmts.User" user "User.Comments")
		(21 "Eco1.User" user "User.Eco1")
		(23 "Eco2.User" user "User.Eco2")
		(25 "Edge.Cuts" user "Board Geometry/Outline")
		(27 "Margin" user)
		(31 "F.CrtYd" user "Package Geometry/Place Bound Top")
		(29 "B.CrtYd" user "Package Geometry/Place Bound Bottom")
		(35 "F.Fab" user "Ref Des/Assembly Top")
		(33 "B.Fab" user "Ref Des/Assembly Bottom")
	)
	(footprint ""
		(layer "B.Cu")
		(at 370.046758 -248.47931)
		(property "Reference" "C2195"
			(at 0 0 0)
			(layer "B.SilkS")
			(hide yes)
			(effects
				(font
					(size 1.27 1.27)
				)
				(justify mirror)
			)
		)
		(property "Value" ""
			(at 0 0 0)
			(layer "B.Fab")
			(effects
				(font
					(size 1.27 1.27)
				)
				(justify mirror)
			)
		)
		(duplicate_pad_numbers_are_jumpers no)
		(fp_line
			(start -0.7874 -0.4064)
			(end -0.7874 0.4064)
			(stroke
				(width 0.1524)
				(type default)
			)
			(layer "B.SilkS")
		)
		(fp_line
			(start -0.7874 0.4064)
			(end 0.7874 0.4064)
			(stroke
				(width 0.1524)
				(type default)
			)
			(layer "B.SilkS")
		)
		(fp_line
			(start 0.7874 -0.4064)
			(end -0.7874 -0.4064)
			(stroke
				(width 0.1524)
				(type default)
			)
			(layer "B.SilkS")
		)
		(fp_line
			(start 0.7874 0.4064)
			(end 0.7874 -0.4064)
			(stroke
				(width 0.1524)
				(type default)
			)
			(layer "B.SilkS")
		)
		(fp_line
			(start -0.67945 -0.3048)
			(end -0.67945 0.3048)
			(stroke
				(width 0.1)
				(type default)
			)
			(layer "B.Fab")
		)
		(fp_line
			(start -0.67945 0.3048)
			(end -0.120396 0.3048)
			(stroke
				(width 0.1)
				(type default)
			)
			(layer "B.Fab")
		)
		(fp_line
			(start -0.12065 -0.3048)
			(end -0.67945 -0.3048)
			(stroke
				(width 0.1)
				(type default)
			)
			(layer "B.Fab")
		)
		(fp_line
			(start -0.12065 -0.2794)
			(end -0.12065 -0.3048)
			(stroke
				(width 0.1)
				(type default)
			)
			(layer "B.Fab")
		)
		(fp_line
			(start -0.120396 0.2794)
			(end 0.12065 0.2794)
			(stroke
				(width 0.1)
				(type default)
			)
			(layer "B.Fab")
		)
		(fp_line
			(start -0.120396 0.3048)
			(end -0.120396 0.2794)
			(stroke
				(width 0.1)
				(type default)
			)
			(layer "B.Fab")
		)
		(fp_line
			(start 0.12065 -0.305054)
			(end 0.12065 -0.2794)
			(stroke
				(width 0.1)
				(type default)
			)
			(layer "B.Fab")
		)
		(fp_line
			(start 0.12065 -0.2794)
			(end -0.12065 -0.2794)
			(stroke
				(width 0.1)
				(type default)
			)
			(layer "B.Fab")
		)
		(fp_line
			(start 0.12065 0.2794)
			(end 0.12065 0.3048)
			(stroke
				(width 0.1)
				(type default)
			)
			(layer "B.Fab")
		)
		(fp_line
			(start 0.12065 0.3048)
			(end 0.67945 0.3048)
			(stroke
				(width 0.1)
				(type default)
			)
			(layer "B.Fab")
		)
		(fp_line
			(start 0.67945 -0.305054)
			(end 0.12065 -0.305054)
			(stroke
				(width 0.1)
				(type default)
			)
			(layer "B.Fab")
		)
		(fp_line
			(start 0.67945 0.3048)
			(end 0.67945 -0.305054)
			(stroke
				(width 0.1)
				(type default)
			)
			(layer "B.Fab")
		)
		(pad "1" smd circle
			(at 0.40005 0 180)
			(size 0 0)
			(layers "B.Cu" "B.Mask" "B.Paste")
			(net "PVDDCR_CPU0_P0")
		)
		(pad "2" smd circle
			(at -0.40005 0 180)
			(size 0 0)
			(layers "B.Cu" "B.Mask" "B.Paste")
			(net "GND")
		)
	)
	(footprint ""
		(layer "B.Cu")
		(at 199.517 -136.652 90)
		(property "Reference" "R8105"
			(at 0 0 90)
			(layer "B.SilkS")
			(hide yes)
			(effects
				(font
					(size 1.27 1.27)
				)
				(justify mirror)
			)
		)
		(property "Value" ""
			(at 0 0 90)
			(layer "B.Fab")
			(effects
				(font
					(size 1.27 1.27)
				)
				(justify mirror)
			)
		)
		(duplicate_pad_numbers_are_jumpers no)
		(fp_line
			(start 0.7874 -0.4064)
			(end -0.7874 -0.4064)
			(stroke
				(width 0.1524)
				(type default)
			)
			(layer "B.SilkS")
		)
		(fp_line
			(start -0.7874 -0.4064)
			(end -0.7874 0.4064)
			(stroke
				(width 0.1524)
				(type default)
			)
			(layer "B.SilkS")
		)
		(fp_line
			(start 0.7874 0.4064)
			(end 0.7874 -0.4064)
			(stroke
				(width 0.1524)
				(type default)
			)
			(layer "B.SilkS")
		)
		(fp_line
			(start -0.7874 0.4064)
			(end 0.7874 0.4064)
			(stroke
				(width 0.1524)
				(type default)
			)
			(layer "B.SilkS")
		)
		(fp_line
			(start 0.67945 -0.305054)
			(end 0.12065 -0.305054)
			(stroke
				(width 0.1)
				(type default)
			)
			(layer "B.Fab")
		)
		(fp_line
			(start 0.12065 -0.305054)
			(end 0.12065 -0.2794)
			(stroke
				(width 0.1)
				(type default)
			)
			(layer "B.Fab")
		)
		(fp_line
			(start -0.12065 -0.3048)
			(end -0.67945 -0.3048)
			(stroke
				(width 0.1)
				(type default)
			)
			(layer "B.Fab")
		)
		(fp_line
			(start -0.67945 -0.3048)
			(end -0.67945 0.3048)
			(stroke
				(width 0.1)
				(type default)
			)
			(layer "B.Fab")
		)
		(fp_line
			(start 0.12065 -0.2794)
			(end -0.12065 -0.2794)
			(stroke
				(width 0.1)
				(type default)
			)
			(layer "B.Fab")
		)
		(fp_line
			(start -0.12065 -0.2794)
			(end -0.12065 -0.3048)
			(stroke
				(width 0.1)
				(type default)
			)
			(layer "B.Fab")
		)
		(fp_line
			(start 0.12065 0.2794)
			(end 0.12065 0.3048)
			(stroke
				(width 0.1)
				(type default)
			)
			(layer "B.Fab")
		)
		(fp_line
			(start -0.120396 0.2794)
			(end 0.12065 0.2794)
			(stroke
				(width 0.1)
				(type default)
			)
			(layer "B.Fab")
		)
		(fp_line
			(start 0.67945 0.3048)
			(end 0.67945 -0.305054)
			(stroke
				(width 0.1)
				(type default)
			)
			(layer "B.Fab")
		)
		(fp_line
			(start 0.12065 0.3048)
			(end 0.67945 0.3048)
			(stroke
				(width 0.1)
				(type default)
			)
			(layer "B.Fab")
		)
		(fp_line
			(start -0.120396 0.3048)
			(end -0.120396 0.2794)
			(stroke
				(width 0.1)
				(type default)
			)
			(layer "B.Fab")
		)
		(fp_line
			(start -0.67945 0.3048)
			(end -0.120396 0.3048)
			(stroke
				(width 0.1)
				(type default)
			)
			(layer "B.Fab")
		)
		(pad "1" smd circle
			(at 0.40005 0 270)
			(size 0 0)
			(layers "B.Cu" "B.Mask" "B.Paste")
			(net "FM_AC_PWR_BTN_PLD_ISO_R_N")
		)
		(pad "2" smd circle
			(at -0.40005 0 270)
			(size 0 0)
			(layers "B.Cu" "B.Mask" "B.Paste")
			(net "FM_AC_PWR_BTN_PLD_ISO_N")
		)
	)
	(footprint ""
		(layer "B.Cu")
		(at 173.71314 -427.92904 180)
		(property "Reference" "R6237"
			(at 0 0 0)
			(layer "B.SilkS")
			(hide yes)
			(effects
				(font
					(size 1.27 1.27)
				)
				(justify mirror)
			)
		)
		(property "Value" ""
			(at 0 0 0)
			(layer "B.Fab")
			(effects
				(font
					(size 1.27 1.27)
				)
				(justify mirror)
			)
		)
		(duplicate_pad_numbers_are_jumpers no)
		(fp_line
			(start 0.7874 0.4064)
			(end 0.7874 -0.4064)
			(stroke
				(width 0.1524)
				(type default)
			)
			(layer "B.SilkS")
		)
		(fp_line
			(start 0.7874 -0.4064)
			(end -0.7874 -0.4064)
			(stroke
				(width 0.1524)
				(type default)
			)
			(layer "B.SilkS")
		)
		(fp_line
			(start -0.7874 0.4064)
			(end 0.7874 0.4064)
			(stroke
				(width 0.1524)
				(type default)
			)
			(layer "B.SilkS")
		)
		(fp_line
			(start -0.7874 -0.4064)
			(end -0.7874 0.4064)
			(stroke
				(width 0.1524)
				(type default)
			)
			(layer "B.SilkS")
		)
		(fp_line
			(start 0.67945 0.3048)
			(end 0.67945 -0.305054)
			(stroke
				(width 0.1)
				(type default)
			)
			(layer "B.Fab")
		)
		(fp_line
			(start 0.67945 -0.305054)
			(end 0.12065 -0.305054)
			(stroke
				(width 0.1)
				(type default)
			)
			(layer "B.Fab")
		)
		(fp_line
			(start 0.12065 0.3048)
			(end 0.67945 0.3048)
			(stroke
				(width 0.1)
				(type default)
			)
			(layer "B.Fab")
		)
		(fp_line
			(start 0.12065 0.2794)
			(end 0.12065 0.3048)
			(stroke
				(width 0.1)
				(type default)
			)
			(layer "B.Fab")
		)
		(fp_line
			(start 0.12065 -0.2794)
			(end -0.12065 -0.2794)
			(stroke
				(width 0.1)
				(type default)
			)
			(layer "B.Fab")
		)
		(fp_line
			(start 0.12065 -0.305054)
			(end 0.12065 -0.2794)
			(stroke
				(width 0.1)
				(type default)
			)
			(layer "B.Fab")
		)
		(fp_line
			(start -0.120396 0.3048)
			(end -0.120396 0.2794)
			(stroke
				(width 0.1)
				(type default)
			)
			(layer "B.Fab")
		)
		(fp_line
			(start -0.120396 0.2794)
			(end 0.12065 0.2794)
			(stroke
				(width 0.1)
				(type default)
			)
			(layer "B.Fab")
		)
		(fp_line
			(start -0.12065 -0.2794)
			(end -0.12065 -0.3048)
			(stroke
				(width 0.1)
				(type default)
			)
			(layer "B.Fab")
		)
		(fp_line
			(start -0.12065 -0.3048)
			(end -0.67945 -0.3048)
			(stroke
				(width 0.1)
				(type default)
			)
			(layer "B.Fab")
		)
		(fp_line
			(start -0.67945 0.3048)
			(end -0.120396 0.3048)
			(stroke
				(width 0.1)
				(type default)
			)
			(layer "B.Fab")
		)
		(fp_line
			(start -0.67945 -0.3048)
			(end -0.67945 0.3048)
			(stroke
				(width 0.1)
				(type default)
			)
			(layer "B.Fab")
		)
		(pad "1" smd circle
			(at 0.40005 0)
			(size 0 0)
			(layers "B.Cu" "B.Mask" "B.Paste")
			(net "A_HSC_LOW_GATE")
		)
		(pad "2" smd circle
			(at -0.40005 0)
			(size 0 0)
			(layers "B.Cu" "B.Mask" "B.Paste")
			(net "GND")
		)
	)
	(footprint ""
		(layer "B.Cu")
		(at 159.14624 -388.011162 -90)
		(property "Reference" "C388"
			(at 0 0 90)
			(layer "B.SilkS")
			(hide yes)
			(effects
				(font
					(size 1.27 1.27)
				)
				(justify mirror)
			)
		)
		(property "Value" ""
			(at 0 0 90)
			(layer "B.Fab")
			(effects
				(font
					(size 1.27 1.27)
				)
				(justify mirror)
			)
		)
		(duplicate_pad_numbers_are_jumpers no)
		(fp_line
			(start -0.299974 0.150114)
			(end 0.299974 0.150114)
			(stroke
				(width 0.1)
				(type default)
			)
			(layer "B.Fab")
		)
		(fp_line
			(start 0.299974 0.150114)
			(end 0.299974 -0.150114)
			(stroke
				(width 0.1)
				(type default)
			)
			(layer "B.Fab")
		)
		(fp_line
			(start -0.299974 -0.150114)
			(end -0.299974 0.150114)
			(stroke
				(width 0.1)
				(type default)
			)
			(layer "B.Fab")
		)
		(fp_line
			(start 0.299974 -0.150114)
			(end -0.299974 -0.150114)
			(stroke
				(width 0.1)
				(type default)
			)
			(layer "B.Fab")
		)
		(pad "1" smd rect
			(at 0.2667 0 90)
			(size 0.3048 0.381)
			(layers "B.Cu" "B.Mask" "B.Paste")
			(net "P0V9_CPU1_RT_2D")
		)
		(pad "2" smd rect
			(at -0.2667 0 90)
			(size 0.3048 0.381)
			(layers "B.Cu" "B.Mask" "B.Paste")
			(net "GND")
		)
	)
	(footprint ""
		(layer "B.Cu")
		(at 136.08558 -153.865834 90)
		(property "Reference" "PR216"
			(at 0 0 90)
			(layer "B.SilkS")
			(hide yes)
			(effects
				(font
					(size 1.27 1.27)
				)
				(justify mirror)
			)
		)
		(property "Value" ""
			(at 0 0 90)
			(layer "B.Fab")
			(effects
				(font
					(size 1.27 1.27)
				)
				(justify mirror)
			)
		)
		(duplicate_pad_numbers_are_jumpers no)
		(fp_line
			(start 0.7874 -0.4064)
			(end -0.7874 -0.4064)
			(stroke
				(width 0.1524)
				(type default)
			)
			(layer "B.SilkS")
		)
		(fp_line
			(start -0.7874 -0.4064)
			(end -0.7874 0.4064)
			(stroke
				(width 0.1524)
				(type default)
			)
			(layer "B.SilkS")
		)
		(fp_line
			(start 0.7874 0.4064)
			(end 0.7874 -0.4064)
			(stroke
				(width 0.1524)
				(type default)
			)
			(layer "B.SilkS")
		)
		(fp_line
			(start -0.7874 0.4064)
			(end 0.7874 0.4064)
			(stroke
				(width 0.1524)
				(type default)
			)
			(layer "B.SilkS")
		)
		(fp_line
			(start 0.67945 -0.305054)
			(end 0.12065 -0.305054)
			(stroke
				(width 0.1)
				(type default)
			)
			(layer "B.Fab")
		)
		(fp_line
			(start 0.12065 -0.305054)
			(end 0.12065 -0.2794)
			(stroke
				(width 0.1)
				(type default)
			)
			(layer "B.Fab")
		)
		(fp_line
			(start -0.12065 -0.3048)
			(end -0.67945 -0.3048)
			(stroke
				(width 0.1)
				(type default)
			)
			(layer "B.Fab")
		)
		(fp_line
			(start -0.67945 -0.3048)
			(end -0.67945 0.3048)
			(stroke
				(width 0.1)
				(type default)
			)
			(layer "B.Fab")
		)
		(fp_line
			(start 0.12065 -0.2794)
			(end -0.12065 -0.2794)
			(stroke
				(width 0.1)
				(type default)
			)
			(layer "B.Fab")
		)
		(fp_line
			(start -0.12065 -0.2794)
			(end -0.12065 -0.3048)
			(stroke
				(width 0.1)
				(type default)
			)
			(layer "B.Fab")
		)
		(fp_line
			(start 0.12065 0.2794)
			(end 0.12065 0.3048)
			(stroke
				(width 0.1)
				(type default)
			)
			(layer "B.Fab")
		)
		(fp_line
			(start -0.120396 0.2794)
			(end 0.12065 0.2794)
			(stroke
				(width 0.1)
				(type default)
			)
			(layer "B.Fab")
		)
		(fp_line
			(start 0.67945 0.3048)
			(end 0.67945 -0.305054)
			(stroke
				(width 0.1)
				(type default)
			)
			(layer "B.Fab")
		)
		(fp_line
			(start 0.12065 0.3048)
			(end 0.67945 0.3048)
			(stroke
				(width 0.1)
				(type default)
			)
			(layer "B.Fab")
		)
		(fp_line
			(start -0.120396 0.3048)
			(end -0.120396 0.2794)
			(stroke
				(width 0.1)
				(type default)
			)
			(layer "B.Fab")
		)
		(fp_line
			(start -0.67945 0.3048)
			(end -0.120396 0.3048)
			(stroke
				(width 0.1)
				(type default)
			)
			(layer "B.Fab")
		)
		(pad "1" smd circle
			(at 0.40005 0 270)
			(size 0 0)
			(layers "B.Cu" "B.Mask" "B.Paste")
			(net "PVDDCR_SOC_P1_VOS3")
		)
		(pad "2" smd circle
			(at -0.40005 0 270)
			(size 0 0)
			(layers "B.Cu" "B.Mask" "B.Paste")
			(net "PVDDCR_SOC_P1")
		)
	)
	(footprint ""
		(layer "B.Cu")
		(at 103.799386 -255.845564 180)
		(property "Reference" "C2453"
			(at 0 0 0)
			(layer "B.SilkS")
			(hide yes)
			(effects
				(font
					(size 1.27 1.27)
				)
				(justify mirror)
			)
		)
		(property "Value" ""
			(at 0 0 0)
			(layer "B.Fab")
			(effects
				(font
					(size 1.27 1.27)
				)
				(justify mirror)
			)
		)
		(duplicate_pad_numbers_are_jumpers no)
		(fp_line
			(start 0.7874 0.4064)
			(end 0.7874 -0.4064)
			(stroke
				(width 0.1524)
				(type default)
			)
			(layer "B.SilkS")
		)
		(fp_line
			(start 0.7874 -0.4064)
			(end -0.7874 -0.4064)
			(stroke
				(width 0.1524)
				(type default)
			)
			(layer "B.SilkS")
		)
		(fp_line
			(start -0.7874 0.4064)
			(end 0.7874 0.4064)
			(stroke
				(width 0.1524)
				(type default)
			)
			(layer "B.SilkS")
		)
		(fp_line
			(start -0.7874 -0.4064)
			(end -0.7874 0.4064)
			(stroke
				(width 0.1524)
				(type default)
			)
			(layer "B.SilkS")
		)
		(fp_line
			(start 0.67945 0.3048)
			(end 0.67945 -0.305054)
			(stroke
				(width 0.1)
				(type default)
			)
			(layer "B.Fab")
		)
		(fp_line
			(start 0.67945 -0.305054)
			(end 0.12065 -0.305054)
			(stroke
				(width 0.1)
				(type default)
			)
			(layer "B.Fab")
		)
		(fp_line
			(start 0.12065 0.3048)
			(end 0.67945 0.3048)
			(stroke
				(width 0.1)
				(type default)
			)
			(layer "B.Fab")
		)
		(fp_line
			(start 0.12065 0.2794)
			(end 0.12065 0.3048)
			(stroke
				(width 0.1)
				(type default)
			)
			(layer "B.Fab")
		)
		(fp_line
			(start 0.12065 -0.2794)
			(end -0.12065 -0.2794)
			(stroke
				(width 0.1)
				(type default)
			)
			(layer "B.Fab")
		)
		(fp_line
			(start 0.12065 -0.305054)
			(end 0.12065 -0.2794)
			(stroke
				(width 0.1)
				(type default)
			)
			(layer "B.Fab")
		)
		(fp_line
			(start -0.120396 0.3048)
			(end -0.120396 0.2794)
			(stroke
				(width 0.1)
				(type default)
			)
			(layer "B.Fab")
		)
		(fp_line
			(start -0.120396 0.2794)
			(end 0.12065 0.2794)
			(stroke
				(width 0.1)
				(type default)
			)
			(layer "B.Fab")
		)
		(fp_line
			(start -0.12065 -0.2794)
			(end -0.12065 -0.3048)
			(stroke
				(width 0.1)
				(type default)
			)
			(layer "B.Fab")
		)
		(fp_line
			(start -0.12065 -0.3048)
			(end -0.67945 -0.3048)
			(stroke
				(width 0.1)
				(type default)
			)
			(layer "B.Fab")
		)
		(fp_line
			(start -0.67945 0.3048)
			(end -0.120396 0.3048)
			(stroke
				(width 0.1)
				(type default)
			)
			(layer "B.Fab")
		)
		(fp_line
			(start -0.67945 -0.3048)
			(end -0.67945 0.3048)
			(stroke
				(width 0.1)
				(type default)
			)
			(layer "B.Fab")
		)
		(pad "1" smd circle
			(at 0.40005 0)
			(size 0 0)
			(layers "B.Cu" "B.Mask" "B.Paste")
			(net "PVDDCR_SOC_P1")
		)
		(pad "2" smd circle
			(at -0.40005 0)
			(size 0 0)
			(layers "B.Cu" "B.Mask" "B.Paste")
			(net "GND")
		)
	)
	(footprint ""
		(layer "B.Cu")
		(at 371.818408 -396.393162 -90)
		(property "Reference" "C1008"
			(at 0 0 90)
			(layer "B.SilkS")
			(hide yes)
			(effects
				(font
					(size 1.27 1.27)
				)
				(justify mirror)
			)
		)
		(property "Value" ""
			(at 0 0 90)
			(layer "B.Fab")
			(effects
				(font
					(size 1.27 1.27)
				)
				(justify mirror)
			)
		)
		(duplicate_pad_numbers_are_jumpers no)
		(fp_line
			(start -0.299974 0.150114)
			(end 0.299974 0.150114)
			(stroke
				(width 0.1)
				(type default)
			)
			(layer "B.Fab")
		)
		(fp_line
			(start 0.299974 0.150114)
			(end 0.299974 -0.150114)
			(stroke
				(width 0.1)
				(type default)
			)
			(layer "B.Fab")
		)
		(fp_line
			(start -0.299974 -0.150114)
			(end -0.299974 0.150114)
			(stroke
				(width 0.1)
				(type default)
			)
			(layer "B.Fab")
		)
		(fp_line
			(start 0.299974 -0.150114)
			(end -0.299974 -0.150114)
			(stroke
				(width 0.1)
				(type default)
			)
			(layer "B.Fab")
		)
		(pad "1" smd rect
			(at 0.2667 0 90)
			(size 0.3048 0.381)
			(layers "B.Cu" "B.Mask" "B.Paste")
			(net "P0V9_CPU0_RT3_2A")
		)
		(pad "2" smd rect
			(at -0.2667 0 90)
			(size 0.3048 0.381)
			(layers "B.Cu" "B.Mask" "B.Paste")
			(net "GND")
		)
	)
	(footprint ""
		(layer "B.Cu")
		(at 239.141 -331.47)
		(property "Reference" "R846"
			(at 0 0 0)
			(layer "B.SilkS")
			(hide yes)
			(effects
				(font
					(size 1.27 1.27)
				)
				(justify mirror)
			)
		)
		(property "Value" ""
			(at 0 0 0)
			(layer "B.Fab")
			(effects
				(font
					(size 1.27 1.27)
				)
				(justify mirror)
			)
		)
		(duplicate_pad_numbers_are_jumpers no)
		(fp_line
			(start -0.32512 -0.175006)
			(end -0.32512 0.175006)
			(stroke
				(width 0.1)
				(type default)
			)
			(layer "B.Fab")
		)
		(fp_line
			(start -0.32512 0.175006)
			(end 0.32512 0.175006)
			(stroke
				(width 0.1)
				(type default)
			)
			(layer "B.Fab")
		)
		(fp_line
			(start 0.32512 -0.175006)
			(end -0.32512 -0.175006)
			(stroke
				(width 0.1)
				(type default)
			)
			(layer "B.Fab")
		)
		(fp_line
			(start 0.32512 0.175006)
			(end 0.32512 -0.175006)
			(stroke
				(width 0.1)
				(type default)
			)
			(layer "B.Fab")
		)
		(pad "1" smd rect
			(at 0.2667 0 180)
			(size 0.3048 0.381)
			(layers "B.Cu" "B.Mask" "B.Paste")
			(net "RT_ROM_SMB_MUX_ADDR1")
		)
		(pad "2" smd rect
			(at -0.2667 0)
			(size 0.3048 0.381)
			(layers "B.Cu" "B.Mask" "B.Paste")
			(net "GND")
		)
	)
)
